(kicad_pcb
	(version 20241229)
	(generator "pcbnew")
	(generator_version "9.0")
	(general
		(thickness 1.711)
		(legacy_teardrops no)
	)
	(paper "A4")
	(title_block
		(title "Antmicro Baseboard for Jetson AGX Thor")
		(date "2026-02-18")
		(rev "1.1.0")
		(company "Antmicro Ltd")
		(comment 1 "www.antmicro.com")
		(comment 9 "footprint 110 of 1170 (J1), pads 162-242 of 699")
	)
	(layers
		(0 "F.Cu" signal)
		(4 "In1.Cu" signal)
		(6 "In2.Cu" signal)
		(8 "In3.Cu" signal)
		(10 "In4.Cu" jumper)
		(12 "In5.Cu" signal)
		(14 "In6.Cu" signal)
		(16 "In7.Cu" signal)
		(18 "In8.Cu" signal)
		(2 "B.Cu" signal)
		(9 "F.Adhes" user "F.Adhesive")
		(11 "B.Adhes" user "B.Adhesive")
		(13 "F.Paste" user)
		(15 "B.Paste" user)
		(5 "F.SilkS" user "F.Silkscreen")
		(7 "B.SilkS" user "B.Silkscreen")
		(1 "F.Mask" user)
		(3 "B.Mask" user)
		(17 "Dwgs.User" user "User.Drawings")
		(19 "Cmts.User" user "User.Comments")
		(21 "Eco1.User" user "User.Eco1")
		(23 "Eco2.User" user "User.Eco2")
		(25 "Edge.Cuts" user)
		(27 "Margin" user)
		(31 "F.CrtYd" user "F.Courtyard")
		(29 "B.CrtYd" user "B.Courtyard")
		(35 "F.Fab" user)
		(33 "B.Fab" user)
	)
	(footprint "antmicro-footprints:Conn_Hermaphroditic_Molex_203456-0003_mirrored"
		(locked yes)
		(layer "F.Cu")
		(at 116.530532 78.15)
		(descr "Mirrored version of: https://www.molex.com/content/dam/molex/molex-dot-com/products/automated/en-us/salesdrawingpdf/203/203456/2034560003_sd.pdf")
		(property "Reference" "J1"
			(at -32.25 -11.2 180)
			(layer "F.SilkS")
			(effects
				(font
					(size 0.7 0.7)
					(thickness 0.15)
				)
				(justify right top)
			)
		)
		(property "Value" "Hermaphroditic_Molex_203456-0003_CUSTOM_Jetson_AGX_Thor_H8mm"
			(at 0.1 12.9 0)
			(layer "F.Fab")
			(effects
				(font
					(size 0.7 0.7)
					(thickness 0.15)
				)
				(justify right top)
			)
		)
		(property "Datasheet" "https://www.molex.com/content/dam/molex/molex-dot-com/products/automated/en-us/salesdrawingpdf/203/203456/2034560003_sd.pdf?inline"
			(at 0.1 0.2 0)
			(layer "F.Fab")
			(hide yes)
			(effects
				(font
					(size 0.7 0.7)
					(thickness 0.15)
				)
				(justify right top)
			)
		)
		(property "Description" "Mirror Mezz Hermaphroditic Connector, 5.50mm Connector Height, BGA-Attach Mounting, 7 Pair, 11 Row, 699 Circuits, 0.76µm Gold Plating, without Pegs"
			(at 0.1 0.2 0)
			(layer "F.Fab")
			(hide yes)
			(effects
				(font
					(size 0.7 0.7)
					(thickness 0.15)
				)
				(justify right top)
			)
		)
		(property "MPN" "203456-0003"
			(at 0 0 0)
			(unlocked yes)
			(layer "F.Fab")
			(hide yes)
			(effects
				(font
					(size 1 1)
					(thickness 0.15)
				)
			)
		)
		(property "Manufacturer" "Molex"
			(at 0 0 0)
			(unlocked yes)
			(layer "F.Fab")
			(hide yes)
			(effects
				(font
					(size 1 1)
					(thickness 0.15)
				)
			)
		)
		(property "Author" "Antmicro"
			(at 0 0 0)
			(unlocked yes)
			(layer "F.Fab")
			(hide yes)
			(effects
				(font
					(size 1 1)
					(thickness 0.15)
				)
			)
		)
		(property "License" "Apache-2.0"
			(at 0 0 0)
			(unlocked yes)
			(layer "F.Fab")
			(hide yes)
			(effects
				(font
					(size 1 1)
					(thickness 0.15)
				)
			)
		)
		(sheetname "/SoM_IO/")
		(sheetfile "som_io.kicad_sch")
		(solder_mask_margin 0.05)
		(attr smd)
		(pad "C40" smd circle
			(at 7.7 4.5 90)
			(size 0.5 0.5)
			(layers "F.Cu" "F.Mask" "F.Paste")
			(net 1 "GND")
			(pinfunction "GND")
			(pintype "passive")
		)
		(pad "C41" smd circle
			(at 8.6 4.5 90)
			(size 0.5 0.5)
			(layers "F.Cu" "F.Mask" "F.Paste")
			(net 170 "/CSI/CAM0.CSI2_D1-")
			(pinfunction "CSI2_D1_N")
			(pintype "input")
		)
		(pad "C42" smd circle
			(at 9.5 4.5 90)
			(size 0.5 0.5)
			(layers "F.Cu" "F.Mask" "F.Paste")
			(net 89 "/CSI/CAM0.CSI2_D1+")
			(pinfunction "CSI2_D1_P")
			(pintype "input")
		)
		(pad "C43" smd circle
			(at 10.4 4.5 90)
			(size 0.5 0.5)
			(layers "F.Cu" "F.Mask" "F.Paste")
			(net 1 "GND")
			(pinfunction "GND")
			(pintype "passive")
		)
		(pad "C44" smd circle
			(at 11.3 4.5 90)
			(size 0.5 0.5)
			(layers "F.Cu" "F.Mask" "F.Paste")
			(net 58 "unconnected-(J1F-CSI5_CLK_P-PadC44)")
			(pinfunction "CSI5_CLK_P")
			(pintype "input+no_connect")
		)
		(pad "C45" smd circle
			(at 12.2 4.5 90)
			(size 0.5 0.5)
			(layers "F.Cu" "F.Mask" "F.Paste")
			(net 127 "unconnected-(J1F-CSI5_CLK_N-PadC45)")
			(pinfunction "CSI5_CLK_N")
			(pintype "input+no_connect")
		)
		(pad "C46" smd circle
			(at 13.1 4.5 90)
			(size 0.5 0.5)
			(layers "F.Cu" "F.Mask" "F.Paste")
			(net 1 "GND")
			(pinfunction "GND")
			(pintype "passive")
		)
		(pad "C47" smd circle
			(at 14 4.5 90)
			(size 0.5 0.5)
			(layers "F.Cu" "F.Mask" "F.Paste")
			(net 102 "/CSI/CAM3.CSI7_D1+")
			(pinfunction "CSI7_D1_P")
			(pintype "input")
		)
		(pad "C48" smd circle
			(at 14.9 4.5 90)
			(size 0.5 0.5)
			(layers "F.Cu" "F.Mask" "F.Paste")
			(net 86 "/CSI/CAM3.CSI7_D1-")
			(pinfunction "CSI7_D1_N")
			(pintype "input")
		)
		(pad "C49" smd circle
			(at 15.8 4.5 90)
			(size 0.5 0.5)
			(layers "F.Cu" "F.Mask" "F.Paste")
			(net 1 "GND")
			(pinfunction "GND")
			(pintype "passive")
		)
		(pad "C50" smd circle
			(at 16.7 4.5 90)
			(size 0.5 0.5)
			(layers "F.Cu" "F.Mask" "F.Paste")
			(net 799 "/SoM_IO2/DP0.TX3_C-")
			(pinfunction "DP0_D3_HDMI_CK_N")
			(pintype "output")
		)
		(pad "C51" smd circle
			(at 17.6 4.5 90)
			(size 0.5 0.5)
			(layers "F.Cu" "F.Mask" "F.Paste")
			(net 746 "/SoM_IO2/DP0.TX3_C+")
			(pinfunction "DP0_D3_HDMI_CK_P")
			(pintype "output")
		)
		(pad "C52" smd circle
			(at 18.5 4.5 90)
			(size 0.5 0.5)
			(layers "F.Cu" "F.Mask" "F.Paste")
			(net 1 "GND")
			(pinfunction "GND")
			(pintype "passive")
		)
		(pad "C53" smd circle
			(at 19.4 4.5 90)
			(size 0.5 0.5)
			(layers "F.Cu" "F.Mask" "F.Paste")
			(net 112 "/SoM_IO/I2C5_SDA_1V8")
			(pinfunction "I2C5_DAT")
			(pintype "bidirectional")
		)
		(pad "C54" smd circle
			(at 20.3 4.5 90)
			(size 0.5 0.5)
			(layers "F.Cu" "F.Mask" "F.Paste")
			(net 750 "unconnected-(J1I-GPIO33-PadC54)")
			(pinfunction "GPIO33")
			(pintype "bidirectional+no_connect")
		)
		(pad "C55" smd circle
			(at 21.2 4.5 90)
			(size 0.5 0.5)
			(layers "F.Cu" "F.Mask" "F.Paste")
			(net 907 "Net-(J1A-GPIO39)")
			(pinfunction "GPIO39")
			(pintype "passive")
		)
		(pad "C56" smd circle
			(at 22.1 4.5 90)
			(size 0.5 0.5)
			(layers "F.Cu" "F.Mask" "F.Paste")
			(net 51 "/Expansion connector/UART2.RX")
			(pinfunction "UART2_RX")
			(pintype "input")
		)
		(pad "C57" smd circle
			(at 23 4.5 90)
			(size 0.5 0.5)
			(layers "F.Cu" "F.Mask" "F.Paste")
			(net 438 "/Expansion connector/SPI3.~{CS0}")
			(pinfunction "SPI3_CS0_N")
			(pintype "bidirectional")
		)
		(pad "C58" smd circle
			(at 23.9 4.5 90)
			(size 0.5 0.5)
			(layers "F.Cu" "F.Mask" "F.Paste")
			(net 61 "/Expansion connector/UART2.TX")
			(pinfunction "UART2_TX")
			(pintype "output")
		)
		(pad "C59" smd circle
			(at 24.8 4.5 90)
			(size 0.5 0.5)
			(layers "F.Cu" "F.Mask" "F.Paste")
			(net 773 "unconnected-(J1H-I2S3_SCLK-PadC59)")
			(pinfunction "I2S3_SCLK")
			(pintype "bidirectional+no_connect")
		)
		(pad "C60" smd circle
			(at 25.7 4.5 90)
			(size 0.5 0.5)
			(layers "F.Cu" "F.Mask" "F.Paste")
			(net 556 "unconnected-(J1H-I2S3_FS-PadC60)")
			(pinfunction "I2S3_FS")
			(pintype "bidirectional+no_connect")
		)
		(pad "C61" smd circle
			(at 26.6 4.5 90)
			(size 0.5 0.5)
			(layers "F.Cu" "F.Mask" "F.Paste")
			(net 448 "/Expansion connector/GPIO.USER_BTN0")
			(pinfunction "GPIO09")
			(pintype "passive")
		)
		(pad "C62" smd circle
			(at 27.5 4.5 90)
			(size 0.5 0.5)
			(layers "F.Cu" "F.Mask" "F.Paste")
			(net 1 "GND")
			(pinfunction "GND")
			(pintype "passive")
		)
		(pad "C63" smd circle
			(at 28.4 4.5 90)
			(size 0.5 0.5)
			(layers "F.Cu" "F.Mask" "F.Paste")
			(net 12 "SYS_VIN_HV")
			(pinfunction "SYS_VIN_HV")
			(pintype "passive")
		)
		(pad "C64" smd circle
			(at 29.3 4.5 90)
			(size 0.5 0.5)
			(layers "F.Cu" "F.Mask" "F.Paste")
			(net 12 "SYS_VIN_HV")
			(pinfunction "SYS_VIN_HV")
			(pintype "passive")
		)
		(pad "C65" smd circle
			(at 30.2 4.5 90)
			(size 0.5 0.5)
			(layers "F.Cu" "F.Mask" "F.Paste")
			(net 12 "SYS_VIN_HV")
			(pinfunction "SYS_VIN_HV")
			(pintype "passive")
		)
		(pad "D1" smd circle
			(at -30 3 90)
			(size 0.5 0.5)
			(layers "F.Cu" "F.Mask" "F.Paste")
			(net 12 "SYS_VIN_HV")
			(pinfunction "SYS_VIN_HV")
			(pintype "passive")
		)
		(pad "D2" smd circle
			(at -29.1 3 90)
			(size 0.5 0.5)
			(layers "F.Cu" "F.Mask" "F.Paste")
			(net 12 "SYS_VIN_HV")
			(pinfunction "SYS_VIN_HV")
			(pintype "passive")
		)
		(pad "D3" smd circle
			(at -28.2 3 90)
			(size 0.5 0.5)
			(layers "F.Cu" "F.Mask" "F.Paste")
			(net 12 "SYS_VIN_HV")
			(pinfunction "SYS_VIN_HV")
			(pintype "passive")
		)
		(pad "D4" smd circle
			(at -27.3 3 90)
			(size 0.5 0.5)
			(layers "F.Cu" "F.Mask" "F.Paste")
			(net 1 "GND")
			(pinfunction "GND")
			(pintype "passive")
		)
		(pad "D5" smd circle
			(at -26.4 3 90)
			(size 0.5 0.5)
			(layers "F.Cu" "F.Mask" "F.Paste")
			(net 47 "/CSI/CAM_CTRL.VSYNC_CAM3")
			(pinfunction "GPIO48")
			(pintype "passive")
		)
		(pad "D6" smd circle
			(at -25.5 3 90)
			(size 0.5 0.5)
			(layers "F.Cu" "F.Mask" "F.Paste")
			(net 918 "unconnected-(J1I-FSI_GPIO33-PadD6)")
			(pinfunction "FSI_GPIO33")
			(pintype "bidirectional+no_connect")
		)
		(pad "D7" smd circle
			(at -24.6 3 90)
			(size 0.5 0.5)
			(layers "F.Cu" "F.Mask" "F.Paste")
			(net 1 "GND")
			(pinfunction "GND")
			(pintype "passive")
		)
		(pad "D8" smd circle
			(at -23.7 3 90)
			(size 0.5 0.5)
			(layers "F.Cu" "F.Mask" "F.Paste")
			(net 150 "/SoM_IO/I2S_{M.2}.FS")
			(pinfunction "I2S1_FS")
			(pintype "bidirectional")
		)
		(pad "D9" smd circle
			(at -22.8 3 90)
			(size 0.5 0.5)
			(layers "F.Cu" "F.Mask" "F.Paste")
			(net 767 "unconnected-(J1G-FSI_GPIO25-PadD9)")
			(pinfunction "FSI_GPIO25")
			(pintype "bidirectional+no_connect")
		)
		(pad "D10" smd circle
			(at -21.9 3 90)
			(size 0.5 0.5)
			(layers "F.Cu" "F.Mask" "F.Paste")
			(net 554 "/Expansion connector/PCIe_{C2x1}.~{RST}")
			(pinfunction "PEX_C2_RST_N")
			(pintype "output")
		)
		(pad "D11" smd circle
			(at -21 3 90)
			(size 0.5 0.5)
			(layers "F.Cu" "F.Mask" "F.Paste")
			(net 1 "GND")
			(pinfunction "GND")
			(pintype "passive")
		)
		(pad "D12" smd circle
			(at -20.1 3 90)
			(size 0.5 0.5)
			(layers "F.Cu" "F.Mask" "F.Paste")
			(net 782 "/Expansion connector/PCIe_{C3x2}.RX1+")
			(pinfunction "UPHY_RX7_P")
			(pintype "input")
		)
		(pad "D13" smd circle
			(at -19.2 3 90)
			(size 0.5 0.5)
			(layers "F.Cu" "F.Mask" "F.Paste")
			(net 722 "/Expansion connector/PCIe_{C3x2}.RX1-")
			(pinfunction "UPHY_RX7_N")
			(pintype "input")
		)
		(pad "D14" smd circle
			(at -18.3 3 90)
			(size 0.5 0.5)
			(layers "F.Cu" "F.Mask" "F.Paste")
			(net 1 "GND")
			(pinfunction "GND")
			(pintype "passive")
		)
		(pad "D15" smd circle
			(at -17 3 90)
			(size 0.5 0.5)
			(layers "F.Cu" "F.Mask" "F.Paste")
			(net 1 "GND")
			(pinfunction "GND")
			(pintype "passive")
		)
		(pad "D16" smd circle
			(at -16.1 3 90)
			(size 0.5 0.5)
			(layers "F.Cu" "F.Mask" "F.Paste")
			(net 1252 "/SoM_IO2/DP1.AUX_C+")
			(pinfunction "DP_AUX_CH1_P")
			(pintype "bidirectional")
		)
		(pad "D17" smd circle
			(at -15.2 3 90)
			(size 0.5 0.5)
			(layers "F.Cu" "F.Mask" "F.Paste")
			(net 1253 "/SoM_IO2/DP1.AUX_C-")
			(pinfunction "DP_AUX_CH1_N")
			(pintype "bidirectional")
		)
		(pad "D18" smd circle
			(at -14.3 3 90)
			(size 0.5 0.5)
			(layers "F.Cu" "F.Mask" "F.Paste")
			(net 1 "GND")
			(pinfunction "GND")
			(pintype "passive")
		)
		(pad "D19" smd circle
			(at -13 3 90)
			(size 0.5 0.5)
			(layers "F.Cu" "F.Mask" "F.Paste")
			(net 1 "GND")
			(pinfunction "GND")
			(pintype "passive")
		)
		(pad "D20" smd circle
			(at -12.1 3 90)
			(size 0.5 0.5)
			(layers "F.Cu" "F.Mask" "F.Paste")
			(net 638 "unconnected-(J1B-UPHY_RX5_P-PadD20)")
			(pinfunction "UPHY_RX5_P")
			(pintype "input+no_connect")
		)
		(pad "D21" smd circle
			(at -11.2 3 90)
			(size 0.5 0.5)
			(layers "F.Cu" "F.Mask" "F.Paste")
			(net 608 "unconnected-(J1B-UPHY_RX5_N-PadD21)")
			(pinfunction "UPHY_RX5_N")
			(pintype "input+no_connect")
		)
		(pad "D22" smd circle
			(at -10.3 3 90)
			(size 0.5 0.5)
			(layers "F.Cu" "F.Mask" "F.Paste")
			(net 1 "GND")
			(pinfunction "GND")
			(pintype "passive")
		)
		(pad "D23" smd circle
			(at -9 3 90)
			(size 0.5 0.5)
			(layers "F.Cu" "F.Mask" "F.Paste")
			(net 1 "GND")
			(pinfunction "GND")
			(pintype "passive")
		)
		(pad "D24" smd circle
			(at -8.1 3 90)
			(size 0.5 0.5)
			(layers "F.Cu" "F.Mask" "F.Paste")
			(net 725 "/M.2/PCIe_{C5x4}.RX0+")
			(pinfunction "UPHY_RX8_P")
			(pintype "input")
		)
		(pad "D25" smd circle
			(at -7.2 3 90)
			(size 0.5 0.5)
			(layers "F.Cu" "F.Mask" "F.Paste")
			(net 669 "/M.2/PCIe_{C5x4}.RX0-")
			(pinfunction "UPHY_RX8_N")
			(pintype "input")
		)
		(pad "D26" smd circle
			(at -6.3 3 90)
			(size 0.5 0.5)
			(layers "F.Cu" "F.Mask" "F.Paste")
			(net 1 "GND")
			(pinfunction "GND")
			(pintype "passive")
		)
		(pad "D27" smd circle
			(at -5 3 90)
			(size 0.5 0.5)
			(layers "F.Cu" "F.Mask" "F.Paste")
			(net 1 "GND")
			(pinfunction "GND")
			(pintype "passive")
		)
		(pad "D28" smd circle
			(at -4.1 3 90)
			(size 0.5 0.5)
			(layers "F.Cu" "F.Mask" "F.Paste")
			(net 101 "/SFP/SFI.RX+")
			(pinfunction "UPHY_RX12_P")
			(pintype "input")
		)
		(pad "D29" smd circle
			(at -3.2 3 90)
			(size 0.5 0.5)
			(layers "F.Cu" "F.Mask" "F.Paste")
			(net 147 "/SFP/SFI.RX-")
			(pinfunction "UPHY_RX12_N")
			(pintype "input")
		)
		(pad "D30" smd circle
			(at -2.3 3 90)
			(size 0.5 0.5)
			(layers "F.Cu" "F.Mask" "F.Paste")
			(net 1 "GND")
			(pinfunction "GND")
			(pintype "passive")
		)
		(pad "D31" smd circle
			(at -1 3 90)
			(size 0.5 0.5)
			(layers "F.Cu" "F.Mask" "F.Paste")
			(net 1 "GND")
			(pinfunction "GND")
			(pintype "passive")
		)
		(pad "D32" smd circle
			(at -0.1 3 90)
			(size 0.5 0.5)
			(layers "F.Cu" "F.Mask" "F.Paste")
			(net 1268 "/SoM_IO2/DP3.TX0_C-")
			(pinfunction "DP3_D0_HDMI_D2_N")
			(pintype "output")
		)
		(pad "D33" smd circle
			(at 0.8 3 90)
			(size 0.5 0.5)
			(layers "F.Cu" "F.Mask" "F.Paste")
			(net 1264 "/SoM_IO2/DP3.TX0_C+")
			(pinfunction "DP3_D0_HDMI_D2_P")
			(pintype "output")
		)
		(pad "D34" smd circle
			(at 1.7 3 90)
			(size 0.5 0.5)
			(layers "F.Cu" "F.Mask" "F.Paste")
			(net 1 "GND")
			(pinfunction "GND")
			(pintype "passive")
		)
		(pad "D35" smd circle
			(at 3 3 90)
			(size 0.5 0.5)
			(layers "F.Cu" "F.Mask" "F.Paste")
			(net 1 "GND")
			(pinfunction "GND")
			(pintype "passive")
		)
		(pad "D36" smd circle
			(at 3.9 3 90)
			(size 0.5 0.5)
			(layers "F.Cu" "F.Mask" "F.Paste")
			(net 636 "unconnected-(J1G-FSI_GPIO11-PadD36)")
			(pinfunction "FSI_GPIO11")
			(pintype "passive+no_connect")
		)
		(pad "D37" smd circle
			(at 4.8 3 90)
			(size 0.5 0.5)
			(layers "F.Cu" "F.Mask" "F.Paste")
			(net 32 "Net-(D1-C)")
			(pinfunction "PMIC_BBATT")
			(pintype "power_in")
		)
		(pad "D38" smd circle
			(at 5.7 3 90)
			(size 0.5 0.5)
			(layers "F.Cu" "F.Mask" "F.Paste")
			(net 1 "GND")
			(pinfunction "GND")
			(pintype "passive")
		)
		(pad "D39" smd circle
			(at 7 3 90)
			(size 0.5 0.5)
			(layers "F.Cu" "F.Mask" "F.Paste")
			(net 1 "GND")
			(pinfunction "GND")
			(pintype "passive")
		)
		(pad "D40" smd circle
			(at 7.9 3 90)
			(size 0.5 0.5)
			(layers "F.Cu" "F.Mask" "F.Paste")
			(net 724 "unconnected-(J1G-FSI_GPIO01-PadD40)")
			(pinfunction "FSI_GPIO01")
			(pintype "passive+no_connect")
		)
		(pad "D41" smd circle
			(at 8.8 3 90)
			(size 0.5 0.5)
			(layers "F.Cu" "F.Mask" "F.Paste")
			(net 1 "GND")
			(pinfunction "GND")
			(pintype "passive")
		)
		(pad "D42" smd circle
			(at 9.7 3 90)
			(size 0.5 0.5)
			(layers "F.Cu" "F.Mask" "F.Paste")
			(net 125 "/CSI/CAM2.CSI5_D0+")
			(pinfunction "CSI5_D0_P")
			(pintype "input")
		)
		(pad "D43" smd circle
			(at 10.6 3 90)
			(size 0.5 0.5)
			(layers "F.Cu" "F.Mask" "F.Paste")
			(net 128 "/CSI/CAM2.CSI5_D0-")
			(pinfunction "CSI5_D0_N")
			(pintype "input")
		)
		(pad "D44" smd circle
			(at 11.5 3 90)
			(size 0.5 0.5)
			(layers "F.Cu" "F.Mask" "F.Paste")
			(net 1 "GND")
			(pinfunction "GND")
			(pintype "passive")
		)
		(pad "D45" smd circle
			(at 12.4 3 90)
			(size 0.5 0.5)
			(layers "F.Cu" "F.Mask" "F.Paste")
			(net 79 "/CSI/CAM2.CSI5_D1-")
			(pinfunction "CSI5_D1_N")
			(pintype "input")
		)
		(pad "D46" smd circle
			(at 13.3 3 90)
			(size 0.5 0.5)
			(layers "F.Cu" "F.Mask" "F.Paste")
			(net 163 "/CSI/CAM2.CSI5_D1+")
			(pinfunction "CSI5_D1_P")
			(pintype "input")
		)
		(pad "D47" smd circle
			(at 14.2 3 90)
			(size 0.5 0.5)
			(layers "F.Cu" "F.Mask" "F.Paste")
			(net 1 "GND")
			(pinfunction "GND")
			(pintype "passive")
		)
		(pad "D48" smd circle
			(at 15.1 3 90)
			(size 0.5 0.5)
			(layers "F.Cu" "F.Mask" "F.Paste")
			(net 676 "/M.2/PCIe_{C1x1}.CLK-")
			(pinfunction "UPHY_REFCLK6_N")
			(pintype "output")
		)
		(pad "D49" smd circle
			(at 16 3 90)
			(size 0.5 0.5)
			(layers "F.Cu" "F.Mask" "F.Paste")
			(net 589 "/M.2/PCIe_{C1x1}.CLK+")
			(pinfunction "UPHY_REFCLK6_P")
			(pintype "output")
		)
		(pad "D50" smd circle
			(at 16.9 3 90)
			(size 0.5 0.5)
			(layers "F.Cu" "F.Mask" "F.Paste")
			(net 1 "GND")
			(pinfunction "GND")
			(pintype "passive")
		)
		(pad "D51" smd circle
			(at 17.8 3 90)
			(size 0.5 0.5)
			(layers "F.Cu" "F.Mask" "F.Paste")
			(net 523 "/SoM_IO2/DP0.TX0_C+")
			(pinfunction "DP0_D0_HDMI_D2_P")
			(pintype "output")
		)
		(pad "D52" smd circle
			(at 18.7 3 90)
			(size 0.5 0.5)
			(layers "F.Cu" "F.Mask" "F.Paste")
			(net 575 "/SoM_IO2/DP0.TX0_C-")
			(pinfunction "DP0_D0_HDMI_D2_N")
			(pintype "output")
		)
		(pad "D53" smd circle
			(at 19.6 3 90)
			(size 0.5 0.5)
			(layers "F.Cu" "F.Mask" "F.Paste")
			(net 1 "GND")
			(pinfunction "GND")
			(pintype "passive")
		)
		(pad "D54" smd circle
			(at 20.5 3 90)
			(size 0.5 0.5)
			(layers "F.Cu" "F.Mask" "F.Paste")
			(net 908 "unconnected-(J1I-GPIO03-PadD54)")
			(pinfunction "GPIO03")
			(pintype "output+no_connect")
		)
		(pad "D55" smd circle
			(at 21.4 3 90)
			(size 0.5 0.5)
			(layers "F.Cu" "F.Mask" "F.Paste")
			(net 65 "/Expansion connector/SPI1.MOSI")
			(pinfunction "SPI1_MOSI")
			(pintype "bidirectional")
		)
	)
)
